#ISCELL
  pure_quanta quanta_title_block_c *
  *
#CELL
  pure_quanta q_cap *
  page70_i1
#CELL
  pure_quanta q_cap *
  page70_i10
#CELL
  pure_quanta q_cap *
  page70_i11
#CELL
  pure_quanta q_cap *
  page70_i12
#CELL
  pure_quanta q_cap *
  page70_i13
#CELL
  pure_quanta q_cap *
  page70_i14
#CELL
  pure_quanta q_cap *
  page70_i15
#CELL
  pure_quanta q_cap *
  page70_i16
#ISCELL
  pure_quanta_power universal_gnd *
  page70_i17
#CELL
  pure_quanta q_cap *
  page70_i18
#ISCELL
  pure_quanta_power universal_gnd *
  page70_i19
#ISCELL
  pure_quanta_power universal_power *
  page70_i2
#CELL
  pure_quanta q_cap *
  page70_i20
#CELL
  pure_quanta q_cap *
  page70_i3
#ISCELL
  pure_quanta_power universal_power *
  page70_i4
#CELL
  pure_quanta q_cap *
  page70_i5
#ISCELL
  pure_quanta_power universal_power *
  page70_i6
#ISCELL
  pure_quanta_power universal_gnd *
  page70_i7
#CELL
  pure_quanta q_cap *
  page70_i8
#CELL
  pure_quanta q_cap *
  page70_i9
